(kicad_pcb
	(version 20260206)
	(generator "pcbnew")
	(generator_version "10.0")
	(general
		(thickness 1.6)
		(legacy_teardrops no)
	)
	(paper "A4")
	(title_block
		(title "04192023_DAF0TMB3IC0_F0TG_MB_C_brd_V02_OCP.brd")
		(comment 1 "Grand Teton / footprints 8008-8014 of 8354")
	)
	(layers
		(0 "F.Cu" signal "TOP")
		(4 "In1.Cu" signal "GND")
		(6 "In2.Cu" signal "IN1")
		(8 "In3.Cu" signal "GND1")
		(10 "In4.Cu" signal "IN2")
		(12 "In5.Cu" signal "GND2")
		(14 "In6.Cu" signal "IN3")
		(16 "In7.Cu" signal "GND3")
		(18 "In8.Cu" signal "VCC")
		(20 "In9.Cu" signal "VCC1")
		(22 "In10.Cu" signal "GND4")
		(24 "In11.Cu" signal "IN4")
		(26 "In12.Cu" signal "GND5")
		(28 "In13.Cu" signal "IN5")
		(30 "In14.Cu" signal "GND6")
		(32 "In15.Cu" signal "IN6")
		(34 "In16.Cu" signal "GND7")
		(2 "B.Cu" signal "BOTTOM")
		(9 "F.Adhes" user "F.Adhesive")
		(11 "B.Adhes" user "B.Adhesive")
		(13 "F.Paste" user "Package Geometry/Pastemask Top")
		(15 "B.Paste" user "Package Geometry/Pastemask Bottom")
		(5 "F.SilkS" user "Ref Des/Silkscreen Top")
		(7 "B.SilkS" user "Ref Des/Silkscreen Bottom")
		(1 "F.Mask" user "Board Geometry/Soldermask Top")
		(3 "B.Mask" user "Board Geometry/Soldermask Bottom")
		(17 "Dwgs.User" user "User.Drawings")
		(19 "Cmts.User" user "User.Comments")
		(21 "Eco1.User" user "User.Eco1")
		(23 "Eco2.User" user "User.Eco2")
		(25 "Edge.Cuts" user "Board Geometry/Outline")
		(27 "Margin" user)
		(31 "F.CrtYd" user "Package Geometry/Place Bound Top")
		(29 "B.CrtYd" user "Package Geometry/Place Bound Bottom")
		(35 "F.Fab" user "Ref Des/Assembly Top")
		(33 "B.Fab" user "Ref Des/Assembly Bottom")
	)
	(footprint ""
		(layer "B.Cu")
		(at 357.044244 -331.408532 -90)
		(property "Reference" "PR444"
			(at 0 0 90)
			(layer "B.SilkS")
			(hide yes)
			(effects
				(font
					(size 1.27 1.27)
				)
				(justify mirror)
			)
		)
		(property "Value" ""
			(at 0 0 90)
			(layer "B.Fab")
			(effects
				(font
					(size 1.27 1.27)
				)
				(justify mirror)
			)
		)
		(duplicate_pad_numbers_are_jumpers no)
		(fp_line
			(start -0.7874 0.4064)
			(end 0.7874 0.4064)
			(stroke
				(width 0.1524)
				(type default)
			)
			(layer "B.SilkS")
		)
		(fp_line
			(start 0.7874 0.4064)
			(end 0.7874 -0.4064)
			(stroke
				(width 0.1524)
				(type default)
			)
			(layer "B.SilkS")
		)
		(fp_line
			(start -0.7874 -0.4064)
			(end -0.7874 0.4064)
			(stroke
				(width 0.1524)
				(type default)
			)
			(layer "B.SilkS")
		)
		(fp_line
			(start 0.7874 -0.4064)
			(end -0.7874 -0.4064)
			(stroke
				(width 0.1524)
				(type default)
			)
			(layer "B.SilkS")
		)
		(fp_line
			(start -0.67945 0.3048)
			(end -0.120396 0.3048)
			(stroke
				(width 0.1)
				(type default)
			)
			(layer "B.Fab")
		)
		(fp_line
			(start -0.120396 0.3048)
			(end -0.120396 0.2794)
			(stroke
				(width 0.1)
				(type default)
			)
			(layer "B.Fab")
		)
		(fp_line
			(start 0.12065 0.3048)
			(end 0.67945 0.3048)
			(stroke
				(width 0.1)
				(type default)
			)
			(layer "B.Fab")
		)
		(fp_line
			(start 0.67945 0.3048)
			(end 0.67945 -0.305054)
			(stroke
				(width 0.1)
				(type default)
			)
			(layer "B.Fab")
		)
		(fp_line
			(start -0.120396 0.2794)
			(end 0.12065 0.2794)
			(stroke
				(width 0.1)
				(type default)
			)
			(layer "B.Fab")
		)
		(fp_line
			(start 0.12065 0.2794)
			(end 0.12065 0.3048)
			(stroke
				(width 0.1)
				(type default)
			)
			(layer "B.Fab")
		)
		(fp_line
			(start -0.12065 -0.2794)
			(end -0.12065 -0.3048)
			(stroke
				(width 0.1)
				(type default)
			)
			(layer "B.Fab")
		)
		(fp_line
			(start 0.12065 -0.2794)
			(end -0.12065 -0.2794)
			(stroke
				(width 0.1)
				(type default)
			)
			(layer "B.Fab")
		)
		(fp_line
			(start -0.67945 -0.3048)
			(end -0.67945 0.3048)
			(stroke
				(width 0.1)
				(type default)
			)
			(layer "B.Fab")
		)
		(fp_line
			(start -0.12065 -0.3048)
			(end -0.67945 -0.3048)
			(stroke
				(width 0.1)
				(type default)
			)
			(layer "B.Fab")
		)
		(fp_line
			(start 0.12065 -0.305054)
			(end 0.12065 -0.2794)
			(stroke
				(width 0.1)
				(type default)
			)
			(layer "B.Fab")
		)
		(fp_line
			(start 0.67945 -0.305054)
			(end 0.12065 -0.305054)
			(stroke
				(width 0.1)
				(type default)
			)
			(layer "B.Fab")
		)
		(pad "1" smd circle
			(at 0.40005 0 90)
			(size 0 0)
			(layers "B.Cu" "B.Mask" "B.Paste")
			(net "PVDDCR_CPU1_P0")
		)
		(pad "2" smd circle
			(at -0.40005 0 90)
			(size 0 0)
			(layers "B.Cu" "B.Mask" "B.Paste")
			(net "GND")
		)
	)
	(footprint ""
		(layer "B.Cu")
		(at 214.43188 -55.971948)
		(property "Reference" "R3764"
			(at 0 0 0)
			(layer "B.SilkS")
			(hide yes)
			(effects
				(font
					(size 1.27 1.27)
				)
				(justify mirror)
			)
		)
		(property "Value" ""
			(at 0 0 0)
			(layer "B.Fab")
			(effects
				(font
					(size 1.27 1.27)
				)
				(justify mirror)
			)
		)
		(duplicate_pad_numbers_are_jumpers no)
		(fp_line
			(start -0.7874 -0.4064)
			(end -0.7874 0.4064)
			(stroke
				(width 0.1524)
				(type default)
			)
			(layer "B.SilkS")
		)
		(fp_line
			(start -0.7874 0.4064)
			(end 0.7874 0.4064)
			(stroke
				(width 0.1524)
				(type default)
			)
			(layer "B.SilkS")
		)
		(fp_line
			(start 0.7874 -0.4064)
			(end -0.7874 -0.4064)
			(stroke
				(width 0.1524)
				(type default)
			)
			(layer "B.SilkS")
		)
		(fp_line
			(start 0.7874 0.4064)
			(end 0.7874 -0.4064)
			(stroke
				(width 0.1524)
				(type default)
			)
			(layer "B.SilkS")
		)
		(fp_line
			(start -0.67945 -0.3048)
			(end -0.67945 0.3048)
			(stroke
				(width 0.1)
				(type default)
			)
			(layer "B.Fab")
		)
		(fp_line
			(start -0.67945 0.3048)
			(end -0.120396 0.3048)
			(stroke
				(width 0.1)
				(type default)
			)
			(layer "B.Fab")
		)
		(fp_line
			(start -0.12065 -0.3048)
			(end -0.67945 -0.3048)
			(stroke
				(width 0.1)
				(type default)
			)
			(layer "B.Fab")
		)
		(fp_line
			(start -0.12065 -0.2794)
			(end -0.12065 -0.3048)
			(stroke
				(width 0.1)
				(type default)
			)
			(layer "B.Fab")
		)
		(fp_line
			(start -0.120396 0.2794)
			(end 0.12065 0.2794)
			(stroke
				(width 0.1)
				(type default)
			)
			(layer "B.Fab")
		)
		(fp_line
			(start -0.120396 0.3048)
			(end -0.120396 0.2794)
			(stroke
				(width 0.1)
				(type default)
			)
			(layer "B.Fab")
		)
		(fp_line
			(start 0.12065 -0.305054)
			(end 0.12065 -0.2794)
			(stroke
				(width 0.1)
				(type default)
			)
			(layer "B.Fab")
		)
		(fp_line
			(start 0.12065 -0.2794)
			(end -0.12065 -0.2794)
			(stroke
				(width 0.1)
				(type default)
			)
			(layer "B.Fab")
		)
		(fp_line
			(start 0.12065 0.2794)
			(end 0.12065 0.3048)
			(stroke
				(width 0.1)
				(type default)
			)
			(layer "B.Fab")
		)
		(fp_line
			(start 0.12065 0.3048)
			(end 0.67945 0.3048)
			(stroke
				(width 0.1)
				(type default)
			)
			(layer "B.Fab")
		)
		(fp_line
			(start 0.67945 -0.305054)
			(end 0.12065 -0.305054)
			(stroke
				(width 0.1)
				(type default)
			)
			(layer "B.Fab")
		)
		(fp_line
			(start 0.67945 0.3048)
			(end 0.67945 -0.305054)
			(stroke
				(width 0.1)
				(type default)
			)
			(layer "B.Fab")
		)
		(pad "1" smd circle
			(at 0.40005 0 180)
			(size 0 0)
			(layers "B.Cu" "B.Mask" "B.Paste")
			(net "GND")
		)
		(pad "2" smd circle
			(at -0.40005 0 180)
			(size 0 0)
			(layers "B.Cu" "B.Mask" "B.Paste")
			(net "INA230_2_A0")
		)
	)
	(footprint ""
		(layer "B.Cu")
		(at 293.80688 -337.984846 -90)
		(property "Reference" "PC169_1"
			(at 0 0 90)
			(layer "B.SilkS")
			(hide yes)
			(effects
				(font
					(size 1.27 1.27)
				)
				(justify mirror)
			)
		)
		(property "Value" ""
			(at 0 0 90)
			(layer "B.Fab")
			(effects
				(font
					(size 1.27 1.27)
				)
				(justify mirror)
			)
		)
		(duplicate_pad_numbers_are_jumpers no)
		(fp_line
			(start -1.524 0.762)
			(end 1.524 0.762)
			(stroke
				(width 0.1524)
				(type default)
			)
			(layer "B.SilkS")
		)
		(fp_line
			(start 1.524 0.762)
			(end 1.524 -0.762)
			(stroke
				(width 0.1524)
				(type default)
			)
			(layer "B.SilkS")
		)
		(fp_line
			(start -1.524 -0.762)
			(end -1.524 0.762)
			(stroke
				(width 0.1524)
				(type default)
			)
			(layer "B.SilkS")
		)
		(fp_line
			(start 1.524 -0.762)
			(end -1.524 -0.762)
			(stroke
				(width 0.1524)
				(type default)
			)
			(layer "B.SilkS")
		)
		(fp_line
			(start -1.1049 0.724916)
			(end -1.1049 -0.724916)
			(stroke
				(width 0.1)
				(type default)
			)
			(layer "B.Fab")
		)
		(fp_line
			(start 1.1049 0.724916)
			(end -1.1049 0.724916)
			(stroke
				(width 0.1)
				(type default)
			)
			(layer "B.Fab")
		)
		(fp_line
			(start -1.1049 -0.724916)
			(end 1.1049 -0.724916)
			(stroke
				(width 0.1)
				(type default)
			)
			(layer "B.Fab")
		)
		(fp_line
			(start 1.1049 -0.724916)
			(end 1.1049 0.724916)
			(stroke
				(width 0.1)
				(type default)
			)
			(layer "B.Fab")
		)
		(pad "1" smd rect
			(at 0.889 0 270)
			(size 1.016 1.27)
			(layers "B.Cu" "B.Mask" "B.Paste")
			(net "PVDDIO_P0")
		)
		(pad "2" smd rect
			(at -0.889 0 270)
			(size 1.016 1.27)
			(layers "B.Cu" "B.Mask" "B.Paste")
			(net "GND")
		)
	)
	(footprint ""
		(layer "B.Cu")
		(at 163.387532 -435.93258 90)
		(property "Reference" "R4129"
			(at 0 0 90)
			(layer "B.SilkS")
			(hide yes)
			(effects
				(font
					(size 1.27 1.27)
				)
				(justify mirror)
			)
		)
		(property "Value" ""
			(at 0 0 90)
			(layer "B.Fab")
			(effects
				(font
					(size 1.27 1.27)
				)
				(justify mirror)
			)
		)
		(duplicate_pad_numbers_are_jumpers no)
		(fp_line
			(start 0.7874 -0.4064)
			(end -0.7874 -0.4064)
			(stroke
				(width 0.1524)
				(type default)
			)
			(layer "B.SilkS")
		)
		(fp_line
			(start -0.7874 -0.4064)
			(end -0.7874 0.4064)
			(stroke
				(width 0.1524)
				(type default)
			)
			(layer "B.SilkS")
		)
		(fp_line
			(start 0.7874 0.4064)
			(end 0.7874 -0.4064)
			(stroke
				(width 0.1524)
				(type default)
			)
			(layer "B.SilkS")
		)
		(fp_line
			(start -0.7874 0.4064)
			(end 0.7874 0.4064)
			(stroke
				(width 0.1524)
				(type default)
			)
			(layer "B.SilkS")
		)
		(fp_line
			(start 0.67945 -0.305054)
			(end 0.12065 -0.305054)
			(stroke
				(width 0.1)
				(type default)
			)
			(layer "B.Fab")
		)
		(fp_line
			(start 0.12065 -0.305054)
			(end 0.12065 -0.2794)
			(stroke
				(width 0.1)
				(type default)
			)
			(layer "B.Fab")
		)
		(fp_line
			(start -0.12065 -0.3048)
			(end -0.67945 -0.3048)
			(stroke
				(width 0.1)
				(type default)
			)
			(layer "B.Fab")
		)
		(fp_line
			(start -0.67945 -0.3048)
			(end -0.67945 0.3048)
			(stroke
				(width 0.1)
				(type default)
			)
			(layer "B.Fab")
		)
		(fp_line
			(start 0.12065 -0.2794)
			(end -0.12065 -0.2794)
			(stroke
				(width 0.1)
				(type default)
			)
			(layer "B.Fab")
		)
		(fp_line
			(start -0.12065 -0.2794)
			(end -0.12065 -0.3048)
			(stroke
				(width 0.1)
				(type default)
			)
			(layer "B.Fab")
		)
		(fp_line
			(start 0.12065 0.2794)
			(end 0.12065 0.3048)
			(stroke
				(width 0.1)
				(type default)
			)
			(layer "B.Fab")
		)
		(fp_line
			(start -0.120396 0.2794)
			(end 0.12065 0.2794)
			(stroke
				(width 0.1)
				(type default)
			)
			(layer "B.Fab")
		)
		(fp_line
			(start 0.67945 0.3048)
			(end 0.67945 -0.305054)
			(stroke
				(width 0.1)
				(type default)
			)
			(layer "B.Fab")
		)
		(fp_line
			(start 0.12065 0.3048)
			(end 0.67945 0.3048)
			(stroke
				(width 0.1)
				(type default)
			)
			(layer "B.Fab")
		)
		(fp_line
			(start -0.120396 0.3048)
			(end -0.120396 0.2794)
			(stroke
				(width 0.1)
				(type default)
			)
			(layer "B.Fab")
		)
		(fp_line
			(start -0.67945 0.3048)
			(end -0.120396 0.3048)
			(stroke
				(width 0.1)
				(type default)
			)
			(layer "B.Fab")
		)
		(pad "1" smd circle
			(at 0.40005 0 270)
			(size 0 0)
			(layers "B.Cu" "B.Mask" "B.Paste")
			(net "P3V3_AUX")
		)
		(pad "2" smd circle
			(at -0.40005 0 270)
			(size 0 0)
			(layers "B.Cu" "B.Mask" "B.Paste")
			(net "PRSNT_CABLE_GPU_B3_ISO_N")
		)
	)
	(footprint ""
		(layer "B.Cu")
		(at 339.646006 -396.393162 -90)
		(property "Reference" "C662"
			(at 0 0 90)
			(layer "B.SilkS")
			(hide yes)
			(effects
				(font
					(size 1.27 1.27)
				)
				(justify mirror)
			)
		)
		(property "Value" ""
			(at 0 0 90)
			(layer "B.Fab")
			(effects
				(font
					(size 1.27 1.27)
				)
				(justify mirror)
			)
		)
		(duplicate_pad_numbers_are_jumpers no)
		(fp_line
			(start -0.299974 0.150114)
			(end 0.299974 0.150114)
			(stroke
				(width 0.1)
				(type default)
			)
			(layer "B.Fab")
		)
		(fp_line
			(start 0.299974 0.150114)
			(end 0.299974 -0.150114)
			(stroke
				(width 0.1)
				(type default)
			)
			(layer "B.Fab")
		)
		(fp_line
			(start -0.299974 -0.150114)
			(end -0.299974 0.150114)
			(stroke
				(width 0.1)
				(type default)
			)
			(layer "B.Fab")
		)
		(fp_line
			(start 0.299974 -0.150114)
			(end -0.299974 -0.150114)
			(stroke
				(width 0.1)
				(type default)
			)
			(layer "B.Fab")
		)
		(pad "1" smd rect
			(at 0.2667 0 90)
			(size 0.3048 0.381)
			(layers "B.Cu" "B.Mask" "B.Paste")
			(net "P0V9_CPU0_RT1_2A")
		)
		(pad "2" smd rect
			(at -0.2667 0 90)
			(size 0.3048 0.381)
			(layers "B.Cu" "B.Mask" "B.Paste")
			(net "GND")
		)
	)
	(footprint ""
		(layer "B.Cu")
		(at 99.103434 -252.599952 180)
		(property "Reference" "C2663"
			(at 0 0 0)
			(layer "B.SilkS")
			(hide yes)
			(effects
				(font
					(size 1.27 1.27)
				)
				(justify mirror)
			)
		)
		(property "Value" ""
			(at 0 0 0)
			(layer "B.Fab")
			(effects
				(font
					(size 1.27 1.27)
				)
				(justify mirror)
			)
		)
		(duplicate_pad_numbers_are_jumpers no)
		(fp_line
			(start 0.7874 0.4064)
			(end 0.7874 -0.4064)
			(stroke
				(width 0.1524)
				(type default)
			)
			(layer "B.SilkS")
		)
		(fp_line
			(start 0.7874 -0.4064)
			(end -0.7874 -0.4064)
			(stroke
				(width 0.1524)
				(type default)
			)
			(layer "B.SilkS")
		)
		(fp_line
			(start -0.7874 0.4064)
			(end 0.7874 0.4064)
			(stroke
				(width 0.1524)
				(type default)
			)
			(layer "B.SilkS")
		)
		(fp_line
			(start -0.7874 -0.4064)
			(end -0.7874 0.4064)
			(stroke
				(width 0.1524)
				(type default)
			)
			(layer "B.SilkS")
		)
		(fp_line
			(start 0.67945 0.3048)
			(end 0.67945 -0.305054)
			(stroke
				(width 0.1)
				(type default)
			)
			(layer "B.Fab")
		)
		(fp_line
			(start 0.67945 -0.305054)
			(end 0.12065 -0.305054)
			(stroke
				(width 0.1)
				(type default)
			)
			(layer "B.Fab")
		)
		(fp_line
			(start 0.12065 0.3048)
			(end 0.67945 0.3048)
			(stroke
				(width 0.1)
				(type default)
			)
			(layer "B.Fab")
		)
		(fp_line
			(start 0.12065 0.2794)
			(end 0.12065 0.3048)
			(stroke
				(width 0.1)
				(type default)
			)
			(layer "B.Fab")
		)
		(fp_line
			(start 0.12065 -0.2794)
			(end -0.12065 -0.2794)
			(stroke
				(width 0.1)
				(type default)
			)
			(layer "B.Fab")
		)
		(fp_line
			(start 0.12065 -0.305054)
			(end 0.12065 -0.2794)
			(stroke
				(width 0.1)
				(type default)
			)
			(layer "B.Fab")
		)
		(fp_line
			(start -0.120396 0.3048)
			(end -0.120396 0.2794)
			(stroke
				(width 0.1)
				(type default)
			)
			(layer "B.Fab")
		)
		(fp_line
			(start -0.120396 0.2794)
			(end 0.12065 0.2794)
			(stroke
				(width 0.1)
				(type default)
			)
			(layer "B.Fab")
		)
		(fp_line
			(start -0.12065 -0.2794)
			(end -0.12065 -0.3048)
			(stroke
				(width 0.1)
				(type default)
			)
			(layer "B.Fab")
		)
		(fp_line
			(start -0.12065 -0.3048)
			(end -0.67945 -0.3048)
			(stroke
				(width 0.1)
				(type default)
			)
			(layer "B.Fab")
		)
		(fp_line
			(start -0.67945 0.3048)
			(end -0.120396 0.3048)
			(stroke
				(width 0.1)
				(type default)
			)
			(layer "B.Fab")
		)
		(fp_line
			(start -0.67945 -0.3048)
			(end -0.67945 0.3048)
			(stroke
				(width 0.1)
				(type default)
			)
			(layer "B.Fab")
		)
		(pad "1" smd circle
			(at 0.40005 0)
			(size 0 0)
			(layers "B.Cu" "B.Mask" "B.Paste")
			(net "PVDD18_S5_P1")
		)
		(pad "2" smd circle
			(at -0.40005 0)
			(size 0 0)
			(layers "B.Cu" "B.Mask" "B.Paste")
			(net "GND")
		)
	)
	(footprint ""
		(layer "B.Cu")
		(at 81.522316 -326.312276 -90)
		(property "Reference" "PC398_1"
			(at 0 0 90)
			(layer "B.SilkS")
			(hide yes)
			(effects
				(font
					(size 1.27 1.27)
				)
				(justify mirror)
			)
		)
		(property "Value" ""
			(at 0 0 90)
			(layer "B.Fab")
			(effects
				(font
					(size 1.27 1.27)
				)
				(justify mirror)
			)
		)
		(duplicate_pad_numbers_are_jumpers no)
		(fp_line
			(start -1.524 0.762)
			(end 1.524 0.762)
			(stroke
				(width 0.1524)
				(type default)
			)
			(layer "B.SilkS")
		)
		(fp_line
			(start 1.524 0.762)
			(end 1.524 -0.762)
			(stroke
				(width 0.1524)
				(type default)
			)
			(layer "B.SilkS")
		)
		(fp_line
			(start -1.524 -0.762)
			(end -1.524 0.762)
			(stroke
				(width 0.1524)
				(type default)
			)
			(layer "B.SilkS")
		)
		(fp_line
			(start 1.524 -0.762)
			(end -1.524 -0.762)
			(stroke
				(width 0.1524)
				(type default)
			)
			(layer "B.SilkS")
		)
		(fp_line
			(start -1.1049 0.724916)
			(end -1.1049 -0.724916)
			(stroke
				(width 0.1)
				(type default)
			)
			(layer "B.Fab")
		)
		(fp_line
			(start 1.1049 0.724916)
			(end -1.1049 0.724916)
			(stroke
				(width 0.1)
				(type default)
			)
			(layer "B.Fab")
		)
		(fp_line
			(start -1.1049 -0.724916)
			(end 1.1049 -0.724916)
			(stroke
				(width 0.1)
				(type default)
			)
			(layer "B.Fab")
		)
		(fp_line
			(start 1.1049 -0.724916)
			(end 1.1049 0.724916)
			(stroke
				(width 0.1)
				(type default)
			)
			(layer "B.Fab")
		)
		(pad "1" smd rect
			(at 0.889 0 270)
			(size 1.016 1.27)
			(layers "B.Cu" "B.Mask" "B.Paste")
			(net "PVDDCR_CPU1_P1")
		)
		(pad "2" smd rect
			(at -0.889 0 270)
			(size 1.016 1.27)
			(layers "B.Cu" "B.Mask" "B.Paste")
			(net "GND")
		)
	)
)
